# T6G (Grand Teton) — schematic netlist excerpt (pin names and nets, part order shuffled) for the footprints in the layout excerpt that follows; sources: Cadence DE-HDL packaged netlist, KiCad conversion of 04192023_DAF0TMB3IC0_F0TG_MB_C_brd_V02_OCP.brd

J102  SCONN288_DDR506112002KQ  IO  pkg DDR288S_1-1VXC  page 104
  VIN_BULK0  = P12V_MEM_CPU1
  RFU0  = NC
  VIN_MGMT  = P3V3_AUX
  HSCL  = I3C_SPD_DDRG_CPU1_SCL
  HSDA  = I3C_SPD_DDRG_CPU1_SDA
  VSS0  = GND
  DQ0_A  = M_G_CPU1_SA_DQ<0>
  VSS1  = GND
  DQ1_A  = M_G_CPU1_SA_DQ<1>
  VSS2  = GND
  DQS0_A_T  = M_G_CPU1_SA_DQS_DP<0>
  DQS0_A_C  = M_G_CPU1_SA_DQS_DN<0>
  VSS3  = GND
  DQ4_A  = M_G_CPU1_SA_DQ<4>
  VSS4  = GND
  DQ5_A  = M_G_CPU1_SA_DQ<5>
  VSS5  = GND
  DQ8_A  = M_G_CPU1_SA_DQ<8>
  VSS6  = GND
  DQ9_A  = M_G_CPU1_SA_DQ<9>
  VSS7  = GND
  DQS1_A_T  = M_G_CPU1_SA_DQS_DP<1>
  DQS1_A_C  = M_G_CPU1_SA_DQS_DN<1>
  VSS8  = GND
  DQ12_A  = M_G_CPU1_SA_DQ<12>
  VSS9  = GND
  DQ13_A  = M_G_CPU1_SA_DQ<13>
  VSS10  = GND
  DQ16_A  = M_G_CPU1_SA_DQ<16>
  VSS11  = GND
  DQ17_A  = M_G_CPU1_SA_DQ<17>
  VSS12  = GND
  DQS2_A_T  = M_G_CPU1_SA_DQS_DP<2>
  DQS2_A_C  = M_G_CPU1_SA_DQS_DN<2>
  VSS13  = GND
  DQ20_A  = M_G_CPU1_SA_DQ<20>
  VSS14  = GND
  DQ21_A  = M_G_CPU1_SA_DQ<21>
  VSS15  = GND
  DQ24_A  = M_G_CPU1_SA_DQ<24>
  VSS16  = GND
  DQ25_A  = M_G_CPU1_SA_DQ<25>
  VSS17  = GND
  DQS3_A_T  = M_G_CPU1_SA_DQS_DP<3>
  DQS3_A_C  = M_G_CPU1_SA_DQS_DN<3>
  VSS18  = GND
  DQ28_A  = M_G_CPU1_SA_DQ<28>
  VSS19  = GND
  DQ29_A  = M_G_CPU1_SA_DQ<29>
  VSS20  = GND
  CB0_A  = M_G_CPU1_SA_CB<0>
  VSS21  = GND
  CB1_A  = M_G_CPU1_SA_CB<1>
  VSS22  = GND
  DQS4_A_T  = M_G_CPU1_SA_DQS_DP<4>
  DQS4_A_C  = M_G_CPU1_SA_DQS_DN<4>
  VSS23  = GND
  CB4_A  = M_G_CPU1_SA_CB<4>
  VSS24  = GND
  CB5_A  = M_G_CPU1_SA_CB<5>
  VSS25  = GND
  ALERT_N  = M_G_CPU1_ALERT_N
  VSS26  = GND
  CS0_A_N  = M_G_CPU1_SA_CS_N<0>
  VSS27  = GND
  CA0_A  = M_G_CPU1_SA_CA<0>
  VSS28  = GND
  CA2_A  = M_G_CPU1_SA_CA<2>
  VSS29  = GND
  CA4_A  = M_G_CPU1_SA_CA<4>
  VSS30  = GND
  CA6_A  = M_G_CPU1_SA_CA<6>
  VSS31  = GND
  PAR_A  = M_G_CPU1_SA_PAR
  VSS32  = GND
  CA0_B  = M_G_CPU1_SB_CA<0>
  VSS33  = GND
  CA2_B  = M_G_CPU1_SB_CA<2>
  VSS34  = GND
  CA4_B  = M_G_CPU1_SB_CA<4>
  VSS35  = GND
  CA6_B  = M_G_CPU1_SB_CA<6>
  VSS36  = GND
  CS0_B_N  = M_G_CPU1_SB_CS_N<0>
  VSS37  = GND
  \lbd||rsp_a_n\  = M_G_CPU1_SA_RSP<0>
  \lbs||rsp_b_n\  = M_G_CPU1_SB_RSP<0>
  VSS38  = GND
  CB4_B  = M_G_CPU1_SB_CB<4>
  VSS39  = GND
  CB5_B  = M_G_CPU1_SB_CB<5>
  VSS40  = GND
  \dqs9_b_t||tdqs9_b_t||dbi4_b_n\  = M_G_CPU1_SB_DQS_DP<9>
  \dqs9_b_c||tdqs9_b_c\  = M_G_CPU1_SB_DQS_DN<9>
  VSS41  = GND
  CB0_B  = M_G_CPU1_SB_CB<0>
  VSS42  = GND
  CB1_B  = M_G_CPU1_SB_CB<1>
  VSS43  = GND
  DQ0_B  = M_G_CPU1_SB_DQ<0>
  VSS44  = GND
  DQ1_B  = M_G_CPU1_SB_DQ<1>
  VSS45  = GND
  DQS0_B_T  = M_G_CPU1_SB_DQS_DP<0>
  DQS0_B_C  = M_G_CPU1_SB_DQS_DN<0>
  VSS46  = GND
  DQ4_B  = M_G_CPU1_SB_DQ<4>
  VSS47  = GND
  DQ5_B  = M_G_CPU1_SB_DQ<5>
  VSS48  = GND
  DQ8_B  = M_G_CPU1_SB_DQ<8>
  VSS49  = GND
  DQ9_B  = M_G_CPU1_SB_DQ<9>
  VSS50  = GND
  DQS1_B_T  = M_G_CPU1_SB_DQS_DP<1>
  DQS1_B_C  = M_G_CPU1_SB_DQS_DN<1>
  VSS51  = GND
  DQ12_B  = M_G_CPU1_SB_DQ<12>
  VSS52  = GND
  DQ13_B  = M_G_CPU1_SB_DQ<13>
  VSS53  = GND
  DQ16_B  = M_G_CPU1_SB_DQ<16>
  VSS54  = GND
  DQ17_B  = M_G_CPU1_SB_DQ<17>
  VSS55  = GND
  DQS2_B_T  = M_G_CPU1_SB_DQS_DP<2>
  DQS2_B_C  = M_G_CPU1_SB_DQS_DN<2>
  VSS56  = GND
  DQ20_B  = M_G_CPU1_SB_DQ<20>
  VSS57  = GND
  DQ21_B  = M_G_CPU1_SB_DQ<21>
  VSS58  = GND
  DQ24_B  = M_G_CPU1_SB_DQ<24>
  VSS59  = GND
  DQ25_B  = M_G_CPU1_SB_DQ<25>
  VSS60  = GND
  DQS3_B_T  = M_G_CPU1_SB_DQS_DP<3>
  DQS3_B_C  = M_G_CPU1_SB_DQS_DN<3>
  VSS61  = GND
  DQ28_B  = M_G_CPU1_SB_DQ<28>
  VSS62  = GND
  DQ29_B  = M_G_CPU1_SB_DQ<29>
  VSS63  = GND
  RFU1  = NC
  VIN_BULK1  = P12V_MEM_CPU1
  VIN_BULK2  = P12V_MEM_CPU1
  \pwr_good||fail_n\  = PWRGD_CHG_CPU1_DIMM0
  HAS  = PD_CHG_CPU1_DIMM0_SAA
  RFU2  = NC
  RFU3  = NC
  VSS64  = GND
  DQ2_A  = M_G_CPU1_SA_DQ<2>
  VSS65  = GND
  DQ3_A  = M_G_CPU1_SA_DQ<3>
  VSS66  = GND
  \dqs5_a_c||tdqs5_a_c||dqs5_a_t||tdqs5_a_t\  = M_G_CPU1_SA_DQS_DN<5>
  \dqs5_a_t||tdqs5_a_t\  = M_G_CPU1_SA_DQS_DP<5>
  VSS67  = GND
  DQ6_A  = M_G_CPU1_SA_DQ<6>
  VSS68  = GND
  DQ7_A  = M_G_CPU1_SA_DQ<7>
  VSS69  = GND
  DQ10_A  = M_G_CPU1_SA_DQ<10>
  VSS70  = GND
  DQ11_A  = M_G_CPU1_SA_DQ<11>
  VSS71  = GND
  \dqs6_a_c||tdqs6_a_c||dqs6_a_t||tdqs6_a_t\  = M_G_CPU1_SA_DQS_DN<6>
  \dqs6_a_t||tdqs6_a_t\  = M_G_CPU1_SA_DQS_DP<6>
  VSS72  = GND
  DQ14_A  = M_G_CPU1_SA_DQ<14>
  VSS73  = GND
  DQ15_A  = M_G_CPU1_SA_DQ<15>
  VSS74  = GND
  DQ18_A  = M_G_CPU1_SA_DQ<18>
  VSS75  = GND
  DQ19_A  = M_G_CPU1_SA_DQ<19>
  VSS76  = GND
  \dqs7_a_c||tdqs7_a_c\  = M_G_CPU1_SA_DQS_DN<7>
  \dqs7_a_t||tdqs7_a_t\  = M_G_CPU1_SA_DQS_DP<7>
  VSS77  = GND
  DQ22_A  = M_G_CPU1_SA_DQ<22>
  VSS78  = GND
  DQ23_A  = M_G_CPU1_SA_DQ<23>
  VSS79  = GND
  DQ26_A  = M_G_CPU1_SA_DQ<26>
  VSS80  = GND
  DQ27_A  = M_G_CPU1_SA_DQ<27>
  VSS81  = GND
  \dqs8_a_c||tdqs8_a_c\  = M_G_CPU1_SA_DQS_DN<8>
  \dqs8_a_t||tdqs8_a_t\  = M_G_CPU1_SA_DQS_DP<8>
  VSS82  = GND
  DQ30_A  = M_G_CPU1_SA_DQ<30>
  VSS83  = GND
  DQ31_A  = M_G_CPU1_SA_DQ<31>
  VSS84  = GND
  CB2_A  = M_G_CPU1_SA_CB<2>
  VSS85  = GND
  CB3_A  = M_G_CPU1_SA_CB<3>
  VSS86  = GND
  \dqs9_a_c||tdqs9_a_c\  = M_G_CPU1_SA_DQS_DN<9>
  \dqs9_a_t||tdqs9_a_t\  = M_G_CPU1_SA_DQS_DP<9>
  VSS87  = GND
  CB6_A  = M_G_CPU1_SA_CB<6>
  VSS88  = GND
  CB7_A  = M_G_CPU1_SA_CB<7>
  VSS89  = GND
  RESET_N  = M_G_CPU1_RESET_N
  VSS90  = GND
  CS1_A_N  = M_G_CPU1_SA_CS_N<1>
  VSS91  = GND
  CA1_A  = M_G_CPU1_SA_CA<1>
  VSS92  = GND
  CA3_A  = M_G_CPU1_SA_CA<3>
  VSS93  = GND
  CA5_A  = M_G_CPU1_SA_CA<5>
  VSS94  = GND
  CK_T  = M_G_CPU1_CLK_DP<0>
  CK_C  = M_G_CPU1_CLK_DN<0>
  VSS95  = GND
  RFU4  = NC
  CA1_B  = M_G_CPU1_SB_CA<1>
  VSS96  = GND
  CA3_B  = M_G_CPU1_SB_CA<3>
  VSS97  = GND
  CA5_B  = M_G_CPU1_SB_CA<5>
  VSS98  = GND
  PAR_B  = M_G_CPU1_SB_PAR
  VSS99  = GND
  CS1_B_N  = M_G_CPU1_SB_CS_N<1>
  VSS100  = GND
  RFU5  = NC
  RFU6  = NC
  VSS101  = GND
  CB6_B  = M_G_CPU1_SB_CB<6>
  VSS102  = GND
  CB7_B  = M_G_CPU1_SB_CB<7>
  VSS103  = GND
  DQS4_B_C  = M_G_CPU1_SB_DQS_DN<4>
  DQS4_B_T  = M_G_CPU1_SB_DQS_DP<4>
  VSS104  = GND
  CB2_B  = M_G_CPU1_SB_CB<2>
  VSS105  = GND
  CB3_B  = M_G_CPU1_SB_CB<3>
  VSS106  = GND
  DQ2_B  = M_G_CPU1_SB_DQ<2>
  VSS107  = GND
  DQ3_B  = M_G_CPU1_SB_DQ<3>
  VSS108  = GND
  \dqs5_b_c||tdqs5_b_c\  = M_G_CPU1_SB_DQS_DN<5>
  \dqs5_b_t||tdqs5_b_t\  = M_G_CPU1_SB_DQS_DP<5>
  VSS109  = GND
  DQ6_B  = M_G_CPU1_SB_DQ<6>
  VSS110  = GND
  DQ7_B  = M_G_CPU1_SB_DQ<7>
  VSS111  = GND
  DQ10_B  = M_G_CPU1_SB_DQ<10>
  VSS112  = GND
  DQ11_B  = M_G_CPU1_SB_DQ<11>
  VSS113  = GND
  \dqs6_b_c||tdqs6_b_c\  = M_G_CPU1_SB_DQS_DN<6>
  \dqs6_b_t||tdqs6_b_t\  = M_G_CPU1_SB_DQS_DP<6>
  VSS114  = GND
  DQ14_B  = M_G_CPU1_SB_DQ<14>
  VSS115  = GND
  DQ15_B  = M_G_CPU1_SB_DQ<15>
  VSS116  = GND
  DQ18_B  = M_G_CPU1_SB_DQ<18>
  VSS117  = GND
  DQ19_B  = M_G_CPU1_SB_DQ<19>
  VSS118  = GND
  \dqs7_b_c||tdqs7_b_c\  = M_G_CPU1_SB_DQS_DN<7>
  \dqs7_b_t||tdqs7_b_t\  = M_G_CPU1_SB_DQS_DP<7>
  VSS119  = GND
  DQ22_B  = M_G_CPU1_SB_DQ<22>
  VSS120  = GND
  DQ23_B  = M_G_CPU1_SB_DQ<23>
  VSS121  = GND
  DQ26_B  = M_G_CPU1_SB_DQ<26>
  VSS122  = GND
  DQ27_B  = M_G_CPU1_SB_DQ<27>
  VSS123  = GND
  \dqs8_b_c||tdqs8_b_c\  = M_G_CPU1_SB_DQS_DN<8>
  \dqs8_b_t||tdqs8_b_t\  = M_G_CPU1_SB_DQS_DP<8>
  VSS124  = GND
  DQ30_B  = M_G_CPU1_SB_DQ<30>
  VSS125  = GND
  DQ31_B  = M_G_CPU1_SB_DQ<31>
  VSS126  = GND
  G1  = GND
  G2  = GND
  G3  = GND

(kicad_pcb
	(version 20260206)
	(generator "pcbnew")
	(generator_version "10.0")
	(general
		(thickness 1.6)
		(legacy_teardrops no)
	)
	(paper "A4")
	(title_block
		(title "04192023_DAF0TMB3IC0_F0TG_MB_C_brd_V02_OCP.brd")
		(comment 1 "Grand Teton / footprint 4934 of 8354 (J102), pads 185-230 of 291")
	)
	(layers
		(0 "F.Cu" signal "TOP")
		(4 "In1.Cu" signal "GND")
		(6 "In2.Cu" signal "IN1")
		(8 "In3.Cu" signal "GND1")
		(10 "In4.Cu" signal "IN2")
		(12 "In5.Cu" signal "GND2")
		(14 "In6.Cu" signal "IN3")
		(16 "In7.Cu" signal "GND3")
		(18 "In8.Cu" signal "VCC")
		(20 "In9.Cu" signal "VCC1")
		(22 "In10.Cu" signal "GND4")
		(24 "In11.Cu" signal "IN4")
		(26 "In12.Cu" signal "GND5")
		(28 "In13.Cu" signal "IN5")
		(30 "In14.Cu" signal "GND6")
		(32 "In15.Cu" signal "IN6")
		(34 "In16.Cu" signal "GND7")
		(2 "B.Cu" signal "BOTTOM")
		(9 "F.Adhes" user "F.Adhesive")
		(11 "B.Adhes" user "B.Adhesive")
		(13 "F.Paste" user "Package Geometry/Pastemask Top")
		(15 "B.Paste" user "Package Geometry/Pastemask Bottom")
		(5 "F.SilkS" user "Ref Des/Silkscreen Top")
		(7 "B.SilkS" user "Ref Des/Silkscreen Bottom")
		(1 "F.Mask" user "Board Geometry/Soldermask Top")
		(3 "B.Mask" user "Board Geometry/Soldermask Bottom")
		(17 "Dwgs.User" user "User.Drawings")
		(19 "Cmts.User" user "User.Comments")
		(21 "Eco1.User" user "User.Eco1")
		(23 "Eco2.User" user "User.Eco2")
		(25 "Edge.Cuts" user "Board Geometry/Outline")
		(27 "Margin" user)
		(31 "F.CrtYd" user "Package Geometry/Place Bound Top")
		(29 "B.CrtYd" user "Package Geometry/Place Bound Bottom")
		(35 "F.Fab" user "Ref Des/Assembly Top")
		(33 "B.Fab" user "Ref Des/Assembly Bottom")
	)
	(footprint ""
		(layer "F.Cu")
		(at 166.47795 -255.560322 180)
		(property "Reference" "J102"
			(at -2.7178 -81.857088 0)
			(unlocked yes)
			(layer "F.SilkS")
			(effects
				(font
					(size 0.7874 0.5842)
					(thickness 0.1524)
				)
			)
		)
		(property "Value" ""
			(at 0 0 180)
			(layer "F.Fab")
			(effects
				(font
					(size 1.27 1.27)
				)
			)
		)
		(duplicate_pad_numbers_are_jumpers no)
		(pad "185" smd rect
			(at 2.050034 -29.325062 90)
			(size 0.519938 1.4986)
			(layers "F.Cu" "F.Mask" "F.Paste")
			(net "M_G_CPU1_SA_DQ<26>")
		)
		(pad "186" smd rect
			(at 2.050034 -28.474924 90)
			(size 0.519938 1.4986)
			(layers "F.Cu" "F.Mask" "F.Paste")
			(net "GND")
		)
		(pad "187" smd rect
			(at 2.050034 -27.62504 90)
			(size 0.519938 1.4986)
			(layers "F.Cu" "F.Mask" "F.Paste")
			(net "M_G_CPU1_SA_DQ<27>")
		)
		(pad "188" smd rect
			(at 2.050034 -26.774902 90)
			(size 0.519938 1.4986)
			(layers "F.Cu" "F.Mask" "F.Paste")
			(net "GND")
		)
		(pad "189" smd rect
			(at 2.050034 -25.925018 90)
			(size 0.519938 1.4986)
			(layers "F.Cu" "F.Mask" "F.Paste")
			(net "M_G_CPU1_SA_DQS_DN<8>")
		)
		(pad "190" smd rect
			(at 2.050034 -25.07488 90)
			(size 0.519938 1.4986)
			(layers "F.Cu" "F.Mask" "F.Paste")
			(net "M_G_CPU1_SA_DQS_DP<8>")
		)
		(pad "191" smd rect
			(at 2.050034 -24.224996 90)
			(size 0.519938 1.4986)
			(layers "F.Cu" "F.Mask" "F.Paste")
			(net "GND")
		)
		(pad "192" smd rect
			(at 2.050034 -23.375112 90)
			(size 0.519938 1.4986)
			(layers "F.Cu" "F.Mask" "F.Paste")
			(net "M_G_CPU1_SA_DQ<30>")
		)
		(pad "193" smd rect
			(at 2.050034 -22.524974 90)
			(size 0.519938 1.4986)
			(layers "F.Cu" "F.Mask" "F.Paste")
			(net "GND")
		)
		(pad "194" smd rect
			(at 2.050034 -21.67509 90)
			(size 0.519938 1.4986)
			(layers "F.Cu" "F.Mask" "F.Paste")
			(net "M_G_CPU1_SA_DQ<31>")
		)
		(pad "195" smd rect
			(at 2.050034 -20.824952 90)
			(size 0.519938 1.4986)
			(layers "F.Cu" "F.Mask" "F.Paste")
			(net "GND")
		)
		(pad "196" smd rect
			(at 2.050034 -19.975068 90)
			(size 0.519938 1.4986)
			(layers "F.Cu" "F.Mask" "F.Paste")
			(net "M_G_CPU1_SA_CB<2>")
		)
		(pad "197" smd rect
			(at 2.050034 -19.12493 90)
			(size 0.519938 1.4986)
			(layers "F.Cu" "F.Mask" "F.Paste")
			(net "GND")
		)
		(pad "198" smd rect
			(at 2.050034 -18.275046 90)
			(size 0.519938 1.4986)
			(layers "F.Cu" "F.Mask" "F.Paste")
			(net "M_G_CPU1_SA_CB<3>")
		)
		(pad "199" smd rect
			(at 2.050034 -17.424908 90)
			(size 0.519938 1.4986)
			(layers "F.Cu" "F.Mask" "F.Paste")
			(net "GND")
		)
		(pad "200" smd rect
			(at 2.050034 -16.575024 90)
			(size 0.519938 1.4986)
			(layers "F.Cu" "F.Mask" "F.Paste")
			(net "M_G_CPU1_SA_DQS_DN<9>")
		)
		(pad "201" smd rect
			(at 2.050034 -15.724886 90)
			(size 0.519938 1.4986)
			(layers "F.Cu" "F.Mask" "F.Paste")
			(net "M_G_CPU1_SA_DQS_DP<9>")
		)
		(pad "202" smd rect
			(at 2.050034 -14.875002 90)
			(size 0.519938 1.4986)
			(layers "F.Cu" "F.Mask" "F.Paste")
			(net "GND")
		)
		(pad "203" smd rect
			(at 2.050034 -14.025118 90)
			(size 0.519938 1.4986)
			(layers "F.Cu" "F.Mask" "F.Paste")
			(net "M_G_CPU1_SA_CB<6>")
		)
		(pad "204" smd rect
			(at 2.050034 -13.17498 90)
			(size 0.519938 1.4986)
			(layers "F.Cu" "F.Mask" "F.Paste")
			(net "GND")
		)
		(pad "205" smd rect
			(at 2.050034 -12.325096 90)
			(size 0.519938 1.4986)
			(layers "F.Cu" "F.Mask" "F.Paste")
			(net "M_G_CPU1_SA_CB<7>")
		)
		(pad "206" smd rect
			(at 2.050034 -11.474958 90)
			(size 0.519938 1.4986)
			(layers "F.Cu" "F.Mask" "F.Paste")
			(net "GND")
		)
		(pad "207" smd rect
			(at 2.050034 -10.625074 90)
			(size 0.519938 1.4986)
			(layers "F.Cu" "F.Mask" "F.Paste")
			(net "M_G_CPU1_RESET_N")
		)
		(pad "208" smd rect
			(at 2.050034 -9.774936 90)
			(size 0.519938 1.4986)
			(layers "F.Cu" "F.Mask" "F.Paste")
			(net "GND")
		)
		(pad "209" smd rect
			(at 2.050034 -8.925052 90)
			(size 0.519938 1.4986)
			(layers "F.Cu" "F.Mask" "F.Paste")
			(net "M_G_CPU1_SA_CS_N<1>")
		)
		(pad "210" smd rect
			(at 2.050034 -8.074914 90)
			(size 0.519938 1.4986)
			(layers "F.Cu" "F.Mask" "F.Paste")
			(net "GND")
		)
		(pad "211" smd rect
			(at 2.050034 -7.22503 90)
			(size 0.519938 1.4986)
			(layers "F.Cu" "F.Mask" "F.Paste")
			(net "M_G_CPU1_SA_CA<1>")
		)
		(pad "212" smd rect
			(at 2.050034 -6.374892 90)
			(size 0.519938 1.4986)
			(layers "F.Cu" "F.Mask" "F.Paste")
			(net "GND")
		)
		(pad "213" smd rect
			(at 2.050034 -5.525008 90)
			(size 0.519938 1.4986)
			(layers "F.Cu" "F.Mask" "F.Paste")
			(net "M_G_CPU1_SA_CA<3>")
		)
		(pad "214" smd rect
			(at 2.050034 -4.675124 90)
			(size 0.519938 1.4986)
			(layers "F.Cu" "F.Mask" "F.Paste")
			(net "GND")
		)
		(pad "215" smd rect
			(at 2.050034 -3.824986 90)
			(size 0.519938 1.4986)
			(layers "F.Cu" "F.Mask" "F.Paste")
			(net "M_G_CPU1_SA_CA<5>")
		)
		(pad "216" smd rect
			(at 2.050034 -2.975102 90)
			(size 0.519938 1.4986)
			(layers "F.Cu" "F.Mask" "F.Paste")
			(net "GND")
		)
		(pad "217" smd rect
			(at 2.050034 -2.124964 90)
			(size 0.519938 1.4986)
			(layers "F.Cu" "F.Mask" "F.Paste")
			(net "M_G_CPU1_CLK_DP<0>")
		)
		(pad "218" smd rect
			(at 2.050034 -1.27508 90)
			(size 0.519938 1.4986)
			(layers "F.Cu" "F.Mask" "F.Paste")
			(net "M_G_CPU1_CLK_DN<0>")
		)
		(pad "219" smd rect
			(at 2.050034 -0.424942 90)
			(size 0.519938 1.4986)
			(layers "F.Cu" "F.Mask" "F.Paste")
			(net "GND")
		)
		(pad "220" smd rect
			(at 2.050034 5.525008 90)
			(size 0.519938 1.4986)
			(layers "F.Cu" "F.Mask" "F.Paste")
			(net "Net_2344")
		)
		(pad "221" smd rect
			(at 2.050034 6.374892 90)
			(size 0.519938 1.4986)
			(layers "F.Cu" "F.Mask" "F.Paste")
			(net "M_G_CPU1_SB_CA<1>")
		)
		(pad "222" smd rect
			(at 2.050034 7.22503 90)
			(size 0.519938 1.4986)
			(layers "F.Cu" "F.Mask" "F.Paste")
			(net "GND")
		)
		(pad "223" smd rect
			(at 2.050034 8.074914 90)
			(size 0.519938 1.4986)
			(layers "F.Cu" "F.Mask" "F.Paste")
			(net "M_G_CPU1_SB_CA<3>")
		)
		(pad "224" smd rect
			(at 2.050034 8.925052 90)
			(size 0.519938 1.4986)
			(layers "F.Cu" "F.Mask" "F.Paste")
			(net "GND")
		)
		(pad "225" smd rect
			(at 2.050034 9.774936 90)
			(size 0.519938 1.4986)
			(layers "F.Cu" "F.Mask" "F.Paste")
			(net "M_G_CPU1_SB_CA<5>")
		)
		(pad "226" smd rect
			(at 2.050034 10.625074 90)
			(size 0.519938 1.4986)
			(layers "F.Cu" "F.Mask" "F.Paste")
			(net "GND")
		)
		(pad "227" smd rect
			(at 2.050034 11.474958 90)
			(size 0.519938 1.4986)
			(layers "F.Cu" "F.Mask" "F.Paste")
			(net "M_G_CPU1_SB_PAR")
		)
		(pad "228" smd rect
			(at 2.050034 12.325096 90)
			(size 0.519938 1.4986)
			(layers "F.Cu" "F.Mask" "F.Paste")
			(net "GND")
		)
		(pad "229" smd rect
			(at 2.050034 13.17498 90)
			(size 0.519938 1.4986)
			(layers "F.Cu" "F.Mask" "F.Paste")
			(net "M_G_CPU1_SB_CS_N<1>")
		)
		(pad "230" smd rect
			(at 2.050034 14.025118 90)
			(size 0.519938 1.4986)
			(layers "F.Cu" "F.Mask" "F.Paste")
			(net "GND")
		)
	)
)
